(kicad_pcb
	(version 20260206)
	(generator "pcbnew")
	(generator_version "10.0")
	(general
		(thickness 1.6)
		(legacy_teardrops no)
	)
	(paper "A4")
	(title_block
		(title "03242023_DA0F0TMBIJ0_F0T_Motherboard_J_brd_V01_OCP.brd")
		(comment 1 "Grand Teton / footprints 861-866 of 6105")
	)
	(layers
		(0 "F.Cu" signal "TOP")
		(4 "In1.Cu" signal "GND")
		(6 "In2.Cu" signal "IN1")
		(8 "In3.Cu" signal "GND1")
		(10 "In4.Cu" signal "IN2")
		(12 "In5.Cu" signal "GND2")
		(14 "In6.Cu" signal "IN3")
		(16 "In7.Cu" signal "GND3")
		(18 "In8.Cu" signal "VCC")
		(20 "In9.Cu" signal "VCC1")
		(22 "In10.Cu" signal "GND4")
		(24 "In11.Cu" signal "IN4")
		(26 "In12.Cu" signal "GND5")
		(28 "In13.Cu" signal "IN5")
		(30 "In14.Cu" signal "GND6")
		(32 "In15.Cu" signal "IN6")
		(34 "In16.Cu" signal "GND7")
		(2 "B.Cu" signal "BOTTOM")
		(9 "F.Adhes" user "F.Adhesive")
		(11 "B.Adhes" user "B.Adhesive")
		(13 "F.Paste" user "Package Geometry/Pastemask Top")
		(15 "B.Paste" user "Package Geometry/Pastemask Bottom")
		(5 "F.SilkS" user "Ref Des/Silkscreen Top")
		(7 "B.SilkS" user "Ref Des/Silkscreen Bottom")
		(1 "F.Mask" user "Board Geometry/Soldermask Top")
		(3 "B.Mask" user "Board Geometry/Soldermask Bottom")
		(17 "Dwgs.User" user "User.Drawings")
		(19 "Cmts.User" user "User.Comments")
		(21 "Eco1.User" user "User.Eco1")
		(23 "Eco2.User" user "User.Eco2")
		(25 "Edge.Cuts" user "Board Geometry/Outline")
		(27 "Margin" user)
		(31 "F.CrtYd" user "Package Geometry/Place Bound Top")
		(29 "B.CrtYd" user "Package Geometry/Place Bound Bottom")
		(35 "F.Fab" user "Ref Des/Assembly Top")
		(33 "B.Fab" user "Ref Des/Assembly Bottom")
	)
	(footprint ""
		(layer "F.Cu")
		(at 442.70549 -368.767614)
		(property "Reference" "C1227"
			(at 0 0 0)
			(layer "F.SilkS")
			(hide yes)
			(effects
				(font
					(size 1.27 1.27)
				)
			)
		)
		(property "Value" ""
			(at 0 0 0)
			(layer "F.Fab")
			(effects
				(font
					(size 1.27 1.27)
				)
			)
		)
		(duplicate_pad_numbers_are_jumpers no)
		(fp_line
			(start -0.7874 -0.4064)
			(end 0.7874 -0.4064)
			(stroke
				(width 0.1524)
				(type default)
			)
			(layer "F.SilkS")
		)
		(fp_line
			(start -0.7874 0.4064)
			(end -0.7874 -0.4064)
			(stroke
				(width 0.1524)
				(type default)
			)
			(layer "F.SilkS")
		)
		(fp_line
			(start 0.7874 -0.4064)
			(end 0.7874 0.4064)
			(stroke
				(width 0.1524)
				(type default)
			)
			(layer "F.SilkS")
		)
		(fp_line
			(start 0.7874 0.4064)
			(end -0.7874 0.4064)
			(stroke
				(width 0.1524)
				(type default)
			)
			(layer "F.SilkS")
		)
		(fp_line
			(start -0.67945 -0.305054)
			(end -0.12065 -0.305054)
			(stroke
				(width 0.1)
				(type default)
			)
			(layer "F.Fab")
		)
		(fp_line
			(start -0.67945 0.3048)
			(end -0.67945 -0.305054)
			(stroke
				(width 0.1)
				(type default)
			)
			(layer "F.Fab")
		)
		(fp_line
			(start -0.12065 -0.305054)
			(end -0.12065 -0.2794)
			(stroke
				(width 0.1)
				(type default)
			)
			(layer "F.Fab")
		)
		(fp_line
			(start -0.12065 -0.2794)
			(end 0.12065 -0.2794)
			(stroke
				(width 0.1)
				(type default)
			)
			(layer "F.Fab")
		)
		(fp_line
			(start -0.12065 0.2794)
			(end -0.12065 0.3048)
			(stroke
				(width 0.1)
				(type default)
			)
			(layer "F.Fab")
		)
		(fp_line
			(start -0.12065 0.3048)
			(end -0.67945 0.3048)
			(stroke
				(width 0.1)
				(type default)
			)
			(layer "F.Fab")
		)
		(fp_line
			(start 0.120396 0.2794)
			(end -0.12065 0.2794)
			(stroke
				(width 0.1)
				(type default)
			)
			(layer "F.Fab")
		)
		(fp_line
			(start 0.120396 0.3048)
			(end 0.120396 0.2794)
			(stroke
				(width 0.1)
				(type default)
			)
			(layer "F.Fab")
		)
		(fp_line
			(start 0.12065 -0.3048)
			(end 0.67945 -0.3048)
			(stroke
				(width 0.1)
				(type default)
			)
			(layer "F.Fab")
		)
		(fp_line
			(start 0.12065 -0.2794)
			(end 0.12065 -0.3048)
			(stroke
				(width 0.1)
				(type default)
			)
			(layer "F.Fab")
		)
		(fp_line
			(start 0.67945 -0.3048)
			(end 0.67945 0.3048)
			(stroke
				(width 0.1)
				(type default)
			)
			(layer "F.Fab")
		)
		(fp_line
			(start 0.67945 0.3048)
			(end 0.120396 0.3048)
			(stroke
				(width 0.1)
				(type default)
			)
			(layer "F.Fab")
		)
		(pad "1" smd circle
			(at -0.40005 0)
			(size 0 0)
			(layers "F.Cu" "F.Mask" "F.Paste")
			(net "P5V")
		)
		(pad "2" smd circle
			(at 0.40005 0)
			(size 0 0)
			(layers "F.Cu" "F.Mask" "F.Paste")
			(net "GND")
		)
	)
	(footprint ""
		(layer "F.Cu")
		(at 188.28258 -29.758386 -90)
		(property "Reference" "PR4003"
			(at 0 0 270)
			(layer "F.SilkS")
			(hide yes)
			(effects
				(font
					(size 1.27 1.27)
				)
			)
		)
		(property "Value" ""
			(at 0 0 270)
			(layer "F.Fab")
			(effects
				(font
					(size 1.27 1.27)
				)
			)
		)
		(duplicate_pad_numbers_are_jumpers no)
		(fp_line
			(start -0.7874 0.4064)
			(end -0.7874 -0.4064)
			(stroke
				(width 0.1524)
				(type default)
			)
			(layer "F.SilkS")
		)
		(fp_line
			(start 0.7874 0.4064)
			(end -0.7874 0.4064)
			(stroke
				(width 0.1524)
				(type default)
			)
			(layer "F.SilkS")
		)
		(fp_line
			(start -0.7874 -0.4064)
			(end 0.7874 -0.4064)
			(stroke
				(width 0.1524)
				(type default)
			)
			(layer "F.SilkS")
		)
		(fp_line
			(start 0.7874 -0.4064)
			(end 0.7874 0.4064)
			(stroke
				(width 0.1524)
				(type default)
			)
			(layer "F.SilkS")
		)
		(fp_line
			(start -0.67945 0.3048)
			(end -0.67945 -0.305054)
			(stroke
				(width 0.1)
				(type default)
			)
			(layer "F.Fab")
		)
		(fp_line
			(start -0.12065 0.3048)
			(end -0.67945 0.3048)
			(stroke
				(width 0.1)
				(type default)
			)
			(layer "F.Fab")
		)
		(fp_line
			(start 0.120396 0.3048)
			(end 0.120396 0.2794)
			(stroke
				(width 0.1)
				(type default)
			)
			(layer "F.Fab")
		)
		(fp_line
			(start 0.67945 0.3048)
			(end 0.120396 0.3048)
			(stroke
				(width 0.1)
				(type default)
			)
			(layer "F.Fab")
		)
		(fp_line
			(start -0.12065 0.2794)
			(end -0.12065 0.3048)
			(stroke
				(width 0.1)
				(type default)
			)
			(layer "F.Fab")
		)
		(fp_line
			(start 0.120396 0.2794)
			(end -0.12065 0.2794)
			(stroke
				(width 0.1)
				(type default)
			)
			(layer "F.Fab")
		)
		(fp_line
			(start -0.12065 -0.2794)
			(end 0.12065 -0.2794)
			(stroke
				(width 0.1)
				(type default)
			)
			(layer "F.Fab")
		)
		(fp_line
			(start 0.12065 -0.2794)
			(end 0.12065 -0.3048)
			(stroke
				(width 0.1)
				(type default)
			)
			(layer "F.Fab")
		)
		(fp_line
			(start 0.12065 -0.3048)
			(end 0.67945 -0.3048)
			(stroke
				(width 0.1)
				(type default)
			)
			(layer "F.Fab")
		)
		(fp_line
			(start 0.67945 -0.3048)
			(end 0.67945 0.3048)
			(stroke
				(width 0.1)
				(type default)
			)
			(layer "F.Fab")
		)
		(fp_line
			(start -0.67945 -0.305054)
			(end -0.12065 -0.305054)
			(stroke
				(width 0.1)
				(type default)
			)
			(layer "F.Fab")
		)
		(fp_line
			(start -0.12065 -0.305054)
			(end -0.12065 -0.2794)
			(stroke
				(width 0.1)
				(type default)
			)
			(layer "F.Fab")
		)
		(pad "1" smd circle
			(at -0.40005 0 270)
			(size 0 0)
			(layers "F.Cu" "F.Mask" "F.Paste")
			(net "P12V_AUX")
		)
		(pad "2" smd circle
			(at 0.40005 0 270)
			(size 0 0)
			(layers "F.Cu" "F.Mask" "F.Paste")
			(net "P12V_SCM_VCC")
		)
	)
	(footprint ""
		(layer "F.Cu")
		(at 105.315004 -247.715278 90)
		(property "Reference" "C222"
			(at 0 0 90)
			(layer "F.SilkS")
			(hide yes)
			(effects
				(font
					(size 1.27 1.27)
				)
			)
		)
		(property "Value" ""
			(at 0 0 90)
			(layer "F.Fab")
			(effects
				(font
					(size 1.27 1.27)
				)
			)
		)
		(duplicate_pad_numbers_are_jumpers no)
		(fp_line
			(start 0.7874 -0.4064)
			(end 0.7874 0.4064)
			(stroke
				(width 0.1524)
				(type default)
			)
			(layer "F.SilkS")
		)
		(fp_line
			(start -0.7874 -0.4064)
			(end 0.7874 -0.4064)
			(stroke
				(width 0.1524)
				(type default)
			)
			(layer "F.SilkS")
		)
		(fp_line
			(start 0.7874 0.4064)
			(end -0.7874 0.4064)
			(stroke
				(width 0.1524)
				(type default)
			)
			(layer "F.SilkS")
		)
		(fp_line
			(start -0.7874 0.4064)
			(end -0.7874 -0.4064)
			(stroke
				(width 0.1524)
				(type default)
			)
			(layer "F.SilkS")
		)
		(fp_line
			(start -0.12065 -0.305054)
			(end -0.12065 -0.2794)
			(stroke
				(width 0.1)
				(type default)
			)
			(layer "F.Fab")
		)
		(fp_line
			(start -0.67945 -0.305054)
			(end -0.12065 -0.305054)
			(stroke
				(width 0.1)
				(type default)
			)
			(layer "F.Fab")
		)
		(fp_line
			(start 0.67945 -0.3048)
			(end 0.67945 0.3048)
			(stroke
				(width 0.1)
				(type default)
			)
			(layer "F.Fab")
		)
		(fp_line
			(start 0.12065 -0.3048)
			(end 0.67945 -0.3048)
			(stroke
				(width 0.1)
				(type default)
			)
			(layer "F.Fab")
		)
		(fp_line
			(start 0.12065 -0.2794)
			(end 0.12065 -0.3048)
			(stroke
				(width 0.1)
				(type default)
			)
			(layer "F.Fab")
		)
		(fp_line
			(start -0.12065 -0.2794)
			(end 0.12065 -0.2794)
			(stroke
				(width 0.1)
				(type default)
			)
			(layer "F.Fab")
		)
		(fp_line
			(start 0.120396 0.2794)
			(end -0.12065 0.2794)
			(stroke
				(width 0.1)
				(type default)
			)
			(layer "F.Fab")
		)
		(fp_line
			(start -0.12065 0.2794)
			(end -0.12065 0.3048)
			(stroke
				(width 0.1)
				(type default)
			)
			(layer "F.Fab")
		)
		(fp_line
			(start 0.67945 0.3048)
			(end 0.120396 0.3048)
			(stroke
				(width 0.1)
				(type default)
			)
			(layer "F.Fab")
		)
		(fp_line
			(start 0.120396 0.3048)
			(end 0.120396 0.2794)
			(stroke
				(width 0.1)
				(type default)
			)
			(layer "F.Fab")
		)
		(fp_line
			(start -0.12065 0.3048)
			(end -0.67945 0.3048)
			(stroke
				(width 0.1)
				(type default)
			)
			(layer "F.Fab")
		)
		(fp_line
			(start -0.67945 0.3048)
			(end -0.67945 -0.305054)
			(stroke
				(width 0.1)
				(type default)
			)
			(layer "F.Fab")
		)
		(pad "1" smd circle
			(at -0.40005 0 90)
			(size 0 0)
			(layers "F.Cu" "F.Mask" "F.Paste")
			(net "PVCCIN_CPU1")
		)
		(pad "2" smd circle
			(at 0.40005 0 90)
			(size 0 0)
			(layers "F.Cu" "F.Mask" "F.Paste")
			(net "GND")
		)
	)
	(footprint ""
		(layer "F.Cu")
		(at 435.17312 -43.262804 180)
		(property "Reference" "R2133"
			(at 0 0 180)
			(layer "F.SilkS")
			(hide yes)
			(effects
				(font
					(size 1.27 1.27)
				)
			)
		)
		(property "Value" ""
			(at 0 0 180)
			(layer "F.Fab")
			(effects
				(font
					(size 1.27 1.27)
				)
			)
		)
		(duplicate_pad_numbers_are_jumpers no)
		(fp_line
			(start 0.7874 0.4064)
			(end -0.7874 0.4064)
			(stroke
				(width 0.1524)
				(type default)
			)
			(layer "F.SilkS")
		)
		(fp_line
			(start 0.7874 -0.4064)
			(end 0.7874 0.4064)
			(stroke
				(width 0.1524)
				(type default)
			)
			(layer "F.SilkS")
		)
		(fp_line
			(start -0.7874 0.4064)
			(end -0.7874 -0.4064)
			(stroke
				(width 0.1524)
				(type default)
			)
			(layer "F.SilkS")
		)
		(fp_line
			(start -0.7874 -0.4064)
			(end 0.7874 -0.4064)
			(stroke
				(width 0.1524)
				(type default)
			)
			(layer "F.SilkS")
		)
		(fp_line
			(start 0.67945 0.3048)
			(end 0.120396 0.3048)
			(stroke
				(width 0.1)
				(type default)
			)
			(layer "F.Fab")
		)
		(fp_line
			(start 0.67945 -0.3048)
			(end 0.67945 0.3048)
			(stroke
				(width 0.1)
				(type default)
			)
			(layer "F.Fab")
		)
		(fp_line
			(start 0.12065 -0.2794)
			(end 0.12065 -0.3048)
			(stroke
				(width 0.1)
				(type default)
			)
			(layer "F.Fab")
		)
		(fp_line
			(start 0.12065 -0.3048)
			(end 0.67945 -0.3048)
			(stroke
				(width 0.1)
				(type default)
			)
			(layer "F.Fab")
		)
		(fp_line
			(start 0.120396 0.3048)
			(end 0.120396 0.2794)
			(stroke
				(width 0.1)
				(type default)
			)
			(layer "F.Fab")
		)
		(fp_line
			(start 0.120396 0.2794)
			(end -0.12065 0.2794)
			(stroke
				(width 0.1)
				(type default)
			)
			(layer "F.Fab")
		)
		(fp_line
			(start -0.12065 0.3048)
			(end -0.67945 0.3048)
			(stroke
				(width 0.1)
				(type default)
			)
			(layer "F.Fab")
		)
		(fp_line
			(start -0.12065 0.2794)
			(end -0.12065 0.3048)
			(stroke
				(width 0.1)
				(type default)
			)
			(layer "F.Fab")
		)
		(fp_line
			(start -0.12065 -0.2794)
			(end 0.12065 -0.2794)
			(stroke
				(width 0.1)
				(type default)
			)
			(layer "F.Fab")
		)
		(fp_line
			(start -0.12065 -0.305054)
			(end -0.12065 -0.2794)
			(stroke
				(width 0.1)
				(type default)
			)
			(layer "F.Fab")
		)
		(fp_line
			(start -0.67945 0.3048)
			(end -0.67945 -0.305054)
			(stroke
				(width 0.1)
				(type default)
			)
			(layer "F.Fab")
		)
		(fp_line
			(start -0.67945 -0.305054)
			(end -0.12065 -0.305054)
			(stroke
				(width 0.1)
				(type default)
			)
			(layer "F.Fab")
		)
		(pad "1" smd circle
			(at -0.40005 0 180)
			(size 0 0)
			(layers "F.Cu" "F.Mask" "F.Paste")
			(net "P3V3_AUX")
		)
		(pad "2" smd circle
			(at 0.40005 0 180)
			(size 0 0)
			(layers "F.Cu" "F.Mask" "F.Paste")
			(net "PU_ESPI_ENABLE_STRAP")
		)
	)
	(footprint ""
		(layer "F.Cu")
		(at 80.381602 -74.901552 -90)
		(property "Reference" "R3093"
			(at 0 0 270)
			(layer "F.SilkS")
			(hide yes)
			(effects
				(font
					(size 1.27 1.27)
				)
			)
		)
		(property "Value" ""
			(at 0 0 270)
			(layer "F.Fab")
			(effects
				(font
					(size 1.27 1.27)
				)
			)
		)
		(duplicate_pad_numbers_are_jumpers no)
		(fp_line
			(start -0.7874 0.4064)
			(end -0.7874 -0.4064)
			(stroke
				(width 0.1524)
				(type default)
			)
			(layer "F.SilkS")
		)
		(fp_line
			(start 0.7874 0.4064)
			(end -0.7874 0.4064)
			(stroke
				(width 0.1524)
				(type default)
			)
			(layer "F.SilkS")
		)
		(fp_line
			(start -0.7874 -0.4064)
			(end 0.7874 -0.4064)
			(stroke
				(width 0.1524)
				(type default)
			)
			(layer "F.SilkS")
		)
		(fp_line
			(start 0.7874 -0.4064)
			(end 0.7874 0.4064)
			(stroke
				(width 0.1524)
				(type default)
			)
			(layer "F.SilkS")
		)
		(fp_line
			(start -0.67945 0.3048)
			(end -0.67945 -0.305054)
			(stroke
				(width 0.1)
				(type default)
			)
			(layer "F.Fab")
		)
		(fp_line
			(start -0.12065 0.3048)
			(end -0.67945 0.3048)
			(stroke
				(width 0.1)
				(type default)
			)
			(layer "F.Fab")
		)
		(fp_line
			(start 0.120396 0.3048)
			(end 0.120396 0.2794)
			(stroke
				(width 0.1)
				(type default)
			)
			(layer "F.Fab")
		)
		(fp_line
			(start 0.67945 0.3048)
			(end 0.120396 0.3048)
			(stroke
				(width 0.1)
				(type default)
			)
			(layer "F.Fab")
		)
		(fp_line
			(start -0.12065 0.2794)
			(end -0.12065 0.3048)
			(stroke
				(width 0.1)
				(type default)
			)
			(layer "F.Fab")
		)
		(fp_line
			(start 0.120396 0.2794)
			(end -0.12065 0.2794)
			(stroke
				(width 0.1)
				(type default)
			)
			(layer "F.Fab")
		)
		(fp_line
			(start -0.12065 -0.2794)
			(end 0.12065 -0.2794)
			(stroke
				(width 0.1)
				(type default)
			)
			(layer "F.Fab")
		)
		(fp_line
			(start 0.12065 -0.2794)
			(end 0.12065 -0.3048)
			(stroke
				(width 0.1)
				(type default)
			)
			(layer "F.Fab")
		)
		(fp_line
			(start 0.12065 -0.3048)
			(end 0.67945 -0.3048)
			(stroke
				(width 0.1)
				(type default)
			)
			(layer "F.Fab")
		)
		(fp_line
			(start 0.67945 -0.3048)
			(end 0.67945 0.3048)
			(stroke
				(width 0.1)
				(type default)
			)
			(layer "F.Fab")
		)
		(fp_line
			(start -0.67945 -0.305054)
			(end -0.12065 -0.305054)
			(stroke
				(width 0.1)
				(type default)
			)
			(layer "F.Fab")
		)
		(fp_line
			(start -0.12065 -0.305054)
			(end -0.12065 -0.2794)
			(stroke
				(width 0.1)
				(type default)
			)
			(layer "F.Fab")
		)
		(pad "1" smd circle
			(at -0.40005 0 270)
			(size 0 0)
			(layers "F.Cu" "F.Mask" "F.Paste")
			(net "LED_PWRGD_PVCCD_HV_CPU1")
		)
		(pad "2" smd circle
			(at 0.40005 0 270)
			(size 0 0)
			(layers "F.Cu" "F.Mask" "F.Paste")
			(net "P3V3_AUX")
		)
	)
	(footprint ""
		(layer "F.Cu")
		(at 159.267144 -53.867304 180)
		(property "Reference" "R3574"
			(at 0 0 180)
			(layer "F.SilkS")
			(hide yes)
			(effects
				(font
					(size 1.27 1.27)
				)
			)
		)
		(property "Value" ""
			(at 0 0 180)
			(layer "F.Fab")
			(effects
				(font
					(size 1.27 1.27)
				)
			)
		)
		(duplicate_pad_numbers_are_jumpers no)
		(fp_line
			(start 0.7874 0.4064)
			(end -0.7874 0.4064)
			(stroke
				(width 0.1524)
				(type default)
			)
			(layer "F.SilkS")
		)
		(fp_line
			(start 0.7874 -0.4064)
			(end 0.7874 0.4064)
			(stroke
				(width 0.1524)
				(type default)
			)
			(layer "F.SilkS")
		)
		(fp_line
			(start -0.7874 0.4064)
			(end -0.7874 -0.4064)
			(stroke
				(width 0.1524)
				(type default)
			)
			(layer "F.SilkS")
		)
		(fp_line
			(start -0.7874 -0.4064)
			(end 0.7874 -0.4064)
			(stroke
				(width 0.1524)
				(type default)
			)
			(layer "F.SilkS")
		)
		(fp_line
			(start 0.67945 0.3048)
			(end 0.120396 0.3048)
			(stroke
				(width 0.1)
				(type default)
			)
			(layer "F.Fab")
		)
		(fp_line
			(start 0.67945 -0.3048)
			(end 0.67945 0.3048)
			(stroke
				(width 0.1)
				(type default)
			)
			(layer "F.Fab")
		)
		(fp_line
			(start 0.12065 -0.2794)
			(end 0.12065 -0.3048)
			(stroke
				(width 0.1)
				(type default)
			)
			(layer "F.Fab")
		)
		(fp_line
			(start 0.12065 -0.3048)
			(end 0.67945 -0.3048)
			(stroke
				(width 0.1)
				(type default)
			)
			(layer "F.Fab")
		)
		(fp_line
			(start 0.120396 0.3048)
			(end 0.120396 0.2794)
			(stroke
				(width 0.1)
				(type default)
			)
			(layer "F.Fab")
		)
		(fp_line
			(start 0.120396 0.2794)
			(end -0.12065 0.2794)
			(stroke
				(width 0.1)
				(type default)
			)
			(layer "F.Fab")
		)
		(fp_line
			(start -0.12065 0.3048)
			(end -0.67945 0.3048)
			(stroke
				(width 0.1)
				(type default)
			)
			(layer "F.Fab")
		)
		(fp_line
			(start -0.12065 0.2794)
			(end -0.12065 0.3048)
			(stroke
				(width 0.1)
				(type default)
			)
			(layer "F.Fab")
		)
		(fp_line
			(start -0.12065 -0.2794)
			(end 0.12065 -0.2794)
			(stroke
				(width 0.1)
				(type default)
			)
			(layer "F.Fab")
		)
		(fp_line
			(start -0.12065 -0.305054)
			(end -0.12065 -0.2794)
			(stroke
				(width 0.1)
				(type default)
			)
			(layer "F.Fab")
		)
		(fp_line
			(start -0.67945 0.3048)
			(end -0.67945 -0.305054)
			(stroke
				(width 0.1)
				(type default)
			)
			(layer "F.Fab")
		)
		(fp_line
			(start -0.67945 -0.305054)
			(end -0.12065 -0.305054)
			(stroke
				(width 0.1)
				(type default)
			)
			(layer "F.Fab")
		)
		(pad "1" smd circle
			(at -0.40005 0 180)
			(size 0 0)
			(layers "F.Cu" "F.Mask" "F.Paste")
			(net "P3V3")
		)
		(pad "2" smd circle
			(at 0.40005 0 180)
			(size 0 0)
			(layers "F.Cu" "F.Mask" "F.Paste")
			(net "VSENSE_P12V_INA230_4_INP")
		)
	)
)
